(kicad_pcb
	(version 20260206)
	(generator "pcbnew")
	(generator_version "10.0")
	(general
		(thickness 1.6)
		(legacy_teardrops no)
	)
	(paper "A4")
	(title_block
		(title "12092022_DA0F0TMDCD0_F0T_Management_Board_D_brd_V3_OCP.brd")
		(comment 1 "Grand Teton / footprints 121-123 of 1440")
	)
	(layers
		(0 "F.Cu" signal "TOP")
		(4 "In1.Cu" signal "GND")
		(6 "In2.Cu" signal "IN1")
		(8 "In3.Cu" signal "GND1")
		(10 "In4.Cu" signal "IN2")
		(12 "In5.Cu" signal "VCC")
		(14 "In6.Cu" signal "VCC1")
		(16 "In7.Cu" signal "IN3")
		(18 "In8.Cu" signal "GND2")
		(20 "In9.Cu" signal "IN4")
		(22 "In10.Cu" signal "GND3")
		(2 "B.Cu" signal "BOTTOM")
		(9 "F.Adhes" user "F.Adhesive")
		(11 "B.Adhes" user "B.Adhesive")
		(13 "F.Paste" user "Package Geometry/Pastemask Top")
		(15 "B.Paste" user "Package Geometry/Pastemask Bottom")
		(5 "F.SilkS" user "Ref Des/Silkscreen Top")
		(7 "B.SilkS" user "Ref Des/Silkscreen Bottom")
		(1 "F.Mask" user "Board Geometry/Soldermask Top")
		(3 "B.Mask" user "Board Geometry/Soldermask Bottom")
		(17 "Dwgs.User" user "User.Drawings")
		(19 "Cmts.User" user "User.Comments")
		(21 "Eco1.User" user "User.Eco1")
		(23 "Eco2.User" user "User.Eco2")
		(25 "Edge.Cuts" user "Board Geometry/Outline")
		(27 "Margin" user)
		(31 "F.CrtYd" user "Package Geometry/Place Bound Top")
		(29 "B.CrtYd" user "Package Geometry/Place Bound Bottom")
		(35 "F.Fab" user "Ref Des/Assembly Top")
		(33 "B.Fab" user "Ref Des/Assembly Bottom")
	)
	(footprint ""
		(layer "F.Cu")
		(at 114.554 -32.004 -90)
		(property "Reference" "X11"
			(at 2.0955 -2.83337 90)
			(unlocked yes)
			(layer "F.SilkS")
			(effects
				(font
					(size 0.7874 0.5842)
					(thickness 0.1524)
				)
				(justify left)
			)
		)
		(property "Value" ""
			(at 0 0 270)
			(layer "F.Fab")
			(effects
				(font
					(size 1.27 1.27)
				)
			)
		)
		(property "Device Type" "TP_TDR_4P_FTS_TH-TP_TDR_4P_DIPA"
			(at 1.30175 1.27 0)
			(unlocked yes)
			(layer "F.Fab")
			(hide yes)
			(effects
				(font
					(size 0.635 0.4064)
					(thickness 0.1524)
				)
			)
		)
		(property "User Part Number" "N_A"
			(at 1.30175 1.27 0)
			(unlocked yes)
			(layer "Cmts.User")
			(hide yes)
			(effects
				(font
					(size 0.635 0.4064)
					(thickness 0.1524)
				)
			)
		)
		(duplicate_pad_numbers_are_jumpers no)
		(fp_line
			(start 0 3.81)
			(end 2.54 3.81)
			(stroke
				(width 0.1524)
				(type default)
			)
			(layer "F.SilkS")
		)
		(fp_line
			(start 2.54 3.81)
			(end 2.54 3.6703)
			(stroke
				(width 0.1524)
				(type default)
			)
			(layer "F.SilkS")
		)
		(fp_line
			(start 0 3.175)
			(end 0 3.81)
			(stroke
				(width 0.1524)
				(type default)
			)
			(layer "F.SilkS")
		)
		(fp_line
			(start 2.54 1.4097)
			(end 2.54 1.1303)
			(stroke
				(width 0.1524)
				(type default)
			)
			(layer "F.SilkS")
		)
		(fp_line
			(start 0 0.635)
			(end 0 1.905)
			(stroke
				(width 0.1524)
				(type default)
			)
			(layer "F.SilkS")
		)
		(fp_line
			(start 2.54 -1.1303)
			(end 2.54 -1.27)
			(stroke
				(width 0.1524)
				(type default)
			)
			(layer "F.SilkS")
		)
		(fp_line
			(start 0 -1.27)
			(end 0 -0.635)
			(stroke
				(width 0.1524)
				(type default)
			)
			(layer "F.SilkS")
		)
		(fp_line
			(start 2.54 -1.27)
			(end 0 -1.27)
			(stroke
				(width 0.1524)
				(type default)
			)
			(layer "F.SilkS")
		)
		(fp_poly
			(pts
				(xy -0.761746 0) (xy -2.285746 -0.762) (xy -2.285746 0.762)
			)
			(stroke
				(width 0)
				(type default)
			)
			(fill yes)
			(layer "F.SilkS")
		)
		(fp_line
			(start 0 3.81)
			(end 2.54 3.81)
			(stroke
				(width 0.1)
				(type default)
			)
			(layer "F.Fab")
		)
		(fp_line
			(start 2.54 3.81)
			(end 2.54 -1.27)
			(stroke
				(width 0.1)
				(type default)
			)
			(layer "F.Fab")
		)
		(fp_line
			(start 0 -1.27)
			(end 0 3.81)
			(stroke
				(width 0.1)
				(type default)
			)
			(layer "F.Fab")
		)
		(fp_line
			(start 2.54 -1.27)
			(end 0 -1.27)
			(stroke
				(width 0.1)
				(type default)
			)
			(layer "F.Fab")
		)
		(fp_poly
			(pts
				(xy -0.761746 0) (xy -2.285746 -0.762) (xy -2.285746 0.762)
			)
			(stroke
				(width 0)
				(type default)
			)
			(fill yes)
			(layer "F.Fab")
		)
		(pad "1" thru_hole circle
			(at 0 0 270)
			(size 1.0033 1.0033)
			(drill 0.249936)
			(layers "*.Cu" "*.Mask")
			(remove_unused_layers no)
			(net "TDR_DIFF_85_IN4_DN")
			(clearance 0.10795)
			(thermal_gap 0.10795)
			(padstack
				(mode front_inner_back)
				(layer "Inner"
					(shape circle)
					(size 0.8001 0.8001)
					(clearance 0.1524)
				)
				(layer "B.Cu"
					(shape circle)
					(size 1.0033 1.0033)
					(clearance 0.10795)
				)
			)
		)
		(pad "2" thru_hole circle
			(at 2.54 0 270)
			(size 1.9939 1.9939)
			(drill 0.249936)
			(layers "*.Cu" "*.Mask")
			(remove_unused_layers no)
			(net "GND_P1")
			(clearance 0.10795)
			(thermal_gap 0.10795)
			(padstack
				(mode front_inner_back)
				(layer "Inner"
					(shape circle)
					(size 0.8001 0.8001)
					(clearance 0.1524)
				)
				(layer "B.Cu"
					(shape circle)
					(size 1.9939 1.9939)
					(clearance 0.10795)
				)
			)
		)
		(pad "3" thru_hole circle
			(at 2.54 2.54 270)
			(size 1.9939 1.9939)
			(drill 0.249936)
			(layers "*.Cu" "*.Mask")
			(remove_unused_layers no)
			(net "GND_P1")
			(clearance 0.10795)
			(thermal_gap 0.10795)
			(padstack
				(mode front_inner_back)
				(layer "Inner"
					(shape circle)
					(size 0.8001 0.8001)
					(clearance 0.1524)
				)
				(layer "B.Cu"
					(shape circle)
					(size 1.9939 1.9939)
					(clearance 0.10795)
				)
			)
		)
		(pad "4" thru_hole circle
			(at 0 2.54 270)
			(size 1.0033 1.0033)
			(drill 0.249936)
			(layers "*.Cu" "*.Mask")
			(remove_unused_layers no)
			(net "TDR_DIFF_85_IN4_DP")
			(clearance 0.10795)
			(thermal_gap 0.10795)
			(padstack
				(mode front_inner_back)
				(layer "Inner"
					(shape circle)
					(size 0.8001 0.8001)
					(clearance 0.1524)
				)
				(layer "B.Cu"
					(shape circle)
					(size 1.0033 1.0033)
					(clearance 0.10795)
				)
			)
		)
	)
	(footprint ""
		(layer "F.Cu")
		(at 78.6892 -34.1122)
		(property "Reference" "R600"
			(at 0 0 0)
			(layer "F.SilkS")
			(hide yes)
			(effects
				(font
					(size 1.27 1.27)
				)
			)
		)
		(property "Value" ""
			(at 0 0 0)
			(layer "F.Fab")
			(effects
				(font
					(size 1.27 1.27)
				)
			)
		)
		(duplicate_pad_numbers_are_jumpers no)
		(fp_line
			(start -0.7874 -0.4064)
			(end 0.7874 -0.4064)
			(stroke
				(width 0.1524)
				(type default)
			)
			(layer "F.SilkS")
		)
		(fp_line
			(start -0.7874 0.4064)
			(end -0.7874 -0.4064)
			(stroke
				(width 0.1524)
				(type default)
			)
			(layer "F.SilkS")
		)
		(fp_line
			(start 0.7874 -0.4064)
			(end 0.7874 0.4064)
			(stroke
				(width 0.1524)
				(type default)
			)
			(layer "F.SilkS")
		)
		(fp_line
			(start 0.7874 0.4064)
			(end -0.7874 0.4064)
			(stroke
				(width 0.1524)
				(type default)
			)
			(layer "F.SilkS")
		)
		(fp_line
			(start -0.67945 -0.305054)
			(end -0.12065 -0.305054)
			(stroke
				(width 0.1)
				(type default)
			)
			(layer "F.Fab")
		)
		(fp_line
			(start -0.67945 0.3048)
			(end -0.67945 -0.305054)
			(stroke
				(width 0.1)
				(type default)
			)
			(layer "F.Fab")
		)
		(fp_line
			(start -0.12065 -0.305054)
			(end -0.12065 -0.2794)
			(stroke
				(width 0.1)
				(type default)
			)
			(layer "F.Fab")
		)
		(fp_line
			(start -0.12065 -0.2794)
			(end 0.12065 -0.2794)
			(stroke
				(width 0.1)
				(type default)
			)
			(layer "F.Fab")
		)
		(fp_line
			(start -0.12065 0.2794)
			(end -0.12065 0.3048)
			(stroke
				(width 0.1)
				(type default)
			)
			(layer "F.Fab")
		)
		(fp_line
			(start -0.12065 0.3048)
			(end -0.67945 0.3048)
			(stroke
				(width 0.1)
				(type default)
			)
			(layer "F.Fab")
		)
		(fp_line
			(start 0.120396 0.2794)
			(end -0.12065 0.2794)
			(stroke
				(width 0.1)
				(type default)
			)
			(layer "F.Fab")
		)
		(fp_line
			(start 0.120396 0.3048)
			(end 0.120396 0.2794)
			(stroke
				(width 0.1)
				(type default)
			)
			(layer "F.Fab")
		)
		(fp_line
			(start 0.12065 -0.3048)
			(end 0.67945 -0.3048)
			(stroke
				(width 0.1)
				(type default)
			)
			(layer "F.Fab")
		)
		(fp_line
			(start 0.12065 -0.2794)
			(end 0.12065 -0.3048)
			(stroke
				(width 0.1)
				(type default)
			)
			(layer "F.Fab")
		)
		(fp_line
			(start 0.67945 -0.3048)
			(end 0.67945 0.3048)
			(stroke
				(width 0.1)
				(type default)
			)
			(layer "F.Fab")
		)
		(fp_line
			(start 0.67945 0.3048)
			(end 0.120396 0.3048)
			(stroke
				(width 0.1)
				(type default)
			)
			(layer "F.Fab")
		)
		(pad "1" smd circle
			(at -0.40005 0)
			(size 0 0)
			(layers "F.Cu" "F.Mask" "F.Paste")
			(net "LED_POSTCODE_4")
		)
		(pad "2" smd circle
			(at 0.40005 0)
			(size 0 0)
			(layers "F.Cu" "F.Mask" "F.Paste")
			(net "LED_POSTCODE_4_R")
		)
	)
	(footprint ""
		(layer "F.Cu")
		(at 70.4342 -27.2796 90)
		(property "Reference" "R869"
			(at 0 0 90)
			(layer "F.SilkS")
			(hide yes)
			(effects
				(font
					(size 1.27 1.27)
				)
			)
		)
		(property "Value" ""
			(at 0 0 90)
			(layer "F.Fab")
			(effects
				(font
					(size 1.27 1.27)
				)
			)
		)
		(duplicate_pad_numbers_are_jumpers no)
		(fp_line
			(start 0.7874 -0.4064)
			(end 0.7874 0.4064)
			(stroke
				(width 0.1524)
				(type default)
			)
			(layer "F.SilkS")
		)
		(fp_line
			(start -0.7874 -0.4064)
			(end 0.7874 -0.4064)
			(stroke
				(width 0.1524)
				(type default)
			)
			(layer "F.SilkS")
		)
		(fp_line
			(start 0.7874 0.4064)
			(end -0.7874 0.4064)
			(stroke
				(width 0.1524)
				(type default)
			)
			(layer "F.SilkS")
		)
		(fp_line
			(start -0.7874 0.4064)
			(end -0.7874 -0.4064)
			(stroke
				(width 0.1524)
				(type default)
			)
			(layer "F.SilkS")
		)
		(fp_line
			(start -0.12065 -0.305054)
			(end -0.12065 -0.2794)
			(stroke
				(width 0.1)
				(type default)
			)
			(layer "F.Fab")
		)
		(fp_line
			(start -0.67945 -0.305054)
			(end -0.12065 -0.305054)
			(stroke
				(width 0.1)
				(type default)
			)
			(layer "F.Fab")
		)
		(fp_line
			(start 0.67945 -0.3048)
			(end 0.67945 0.3048)
			(stroke
				(width 0.1)
				(type default)
			)
			(layer "F.Fab")
		)
		(fp_line
			(start 0.12065 -0.3048)
			(end 0.67945 -0.3048)
			(stroke
				(width 0.1)
				(type default)
			)
			(layer "F.Fab")
		)
		(fp_line
			(start 0.12065 -0.2794)
			(end 0.12065 -0.3048)
			(stroke
				(width 0.1)
				(type default)
			)
			(layer "F.Fab")
		)
		(fp_line
			(start -0.12065 -0.2794)
			(end 0.12065 -0.2794)
			(stroke
				(width 0.1)
				(type default)
			)
			(layer "F.Fab")
		)
		(fp_line
			(start 0.120396 0.2794)
			(end -0.12065 0.2794)
			(stroke
				(width 0.1)
				(type default)
			)
			(layer "F.Fab")
		)
		(fp_line
			(start -0.12065 0.2794)
			(end -0.12065 0.3048)
			(stroke
				(width 0.1)
				(type default)
			)
			(layer "F.Fab")
		)
		(fp_line
			(start 0.67945 0.3048)
			(end 0.120396 0.3048)
			(stroke
				(width 0.1)
				(type default)
			)
			(layer "F.Fab")
		)
		(fp_line
			(start 0.120396 0.3048)
			(end 0.120396 0.2794)
			(stroke
				(width 0.1)
				(type default)
			)
			(layer "F.Fab")
		)
		(fp_line
			(start -0.12065 0.3048)
			(end -0.67945 0.3048)
			(stroke
				(width 0.1)
				(type default)
			)
			(layer "F.Fab")
		)
		(fp_line
			(start -0.67945 0.3048)
			(end -0.67945 -0.305054)
			(stroke
				(width 0.1)
				(type default)
			)
			(layer "F.Fab")
		)
		(pad "1" smd circle
			(at -0.40005 0 90)
			(size 0 0)
			(layers "F.Cu" "F.Mask" "F.Paste")
			(net "PWRGD_P1V8_AUX_R3")
		)
		(pad "2" smd circle
			(at 0.40005 0 90)
			(size 0 0)
			(layers "F.Cu" "F.Mask" "F.Paste")
			(net "EN_P3V3_RGM_R")
		)
	)
)
